(kicad_pcb
	(version 20260206)
	(generator "pcbnew")
	(generator_version "10.0")
	(general
		(thickness 1.6)
		(legacy_teardrops no)
	)
	(paper "A4")
	(title_block
		(title "03242023_DA0F0TMBIJ0_F0T_Motherboard_J_brd_V01_OCP.brd")
		(comment 1 "Grand Teton / footprints 1730-1737 of 6105")
	)
	(layers
		(0 "F.Cu" signal "TOP")
		(4 "In1.Cu" signal "GND")
		(6 "In2.Cu" signal "IN1")
		(8 "In3.Cu" signal "GND1")
		(10 "In4.Cu" signal "IN2")
		(12 "In5.Cu" signal "GND2")
		(14 "In6.Cu" signal "IN3")
		(16 "In7.Cu" signal "GND3")
		(18 "In8.Cu" signal "VCC")
		(20 "In9.Cu" signal "VCC1")
		(22 "In10.Cu" signal "GND4")
		(24 "In11.Cu" signal "IN4")
		(26 "In12.Cu" signal "GND5")
		(28 "In13.Cu" signal "IN5")
		(30 "In14.Cu" signal "GND6")
		(32 "In15.Cu" signal "IN6")
		(34 "In16.Cu" signal "GND7")
		(2 "B.Cu" signal "BOTTOM")
		(9 "F.Adhes" user "F.Adhesive")
		(11 "B.Adhes" user "B.Adhesive")
		(13 "F.Paste" user "Package Geometry/Pastemask Top")
		(15 "B.Paste" user "Package Geometry/Pastemask Bottom")
		(5 "F.SilkS" user "Ref Des/Silkscreen Top")
		(7 "B.SilkS" user "Ref Des/Silkscreen Bottom")
		(1 "F.Mask" user "Board Geometry/Soldermask Top")
		(3 "B.Mask" user "Board Geometry/Soldermask Bottom")
		(17 "Dwgs.User" user "User.Drawings")
		(19 "Cmts.User" user "User.Comments")
		(21 "Eco1.User" user "User.Eco1")
		(23 "Eco2.User" user "User.Eco2")
		(25 "Edge.Cuts" user "Board Geometry/Outline")
		(27 "Margin" user)
		(31 "F.CrtYd" user "Package Geometry/Place Bound Top")
		(29 "B.CrtYd" user "Package Geometry/Place Bound Bottom")
		(35 "F.Fab" user "Ref Des/Assembly Top")
		(33 "B.Fab" user "Ref Des/Assembly Bottom")
	)
	(footprint ""
		(layer "F.Cu")
		(at 32.780478 -438.704228)
		(property "Reference" "R3522"
			(at 0 0 0)
			(layer "F.SilkS")
			(hide yes)
			(effects
				(font
					(size 1.27 1.27)
				)
			)
		)
		(property "Value" ""
			(at 0 0 0)
			(layer "F.Fab")
			(effects
				(font
					(size 1.27 1.27)
				)
			)
		)
		(duplicate_pad_numbers_are_jumpers no)
		(fp_line
			(start -0.7874 -0.4064)
			(end 0.7874 -0.4064)
			(stroke
				(width 0.1524)
				(type default)
			)
			(layer "F.SilkS")
		)
		(fp_line
			(start -0.7874 0.4064)
			(end -0.7874 -0.4064)
			(stroke
				(width 0.1524)
				(type default)
			)
			(layer "F.SilkS")
		)
		(fp_line
			(start 0.7874 -0.4064)
			(end 0.7874 0.4064)
			(stroke
				(width 0.1524)
				(type default)
			)
			(layer "F.SilkS")
		)
		(fp_line
			(start 0.7874 0.4064)
			(end -0.7874 0.4064)
			(stroke
				(width 0.1524)
				(type default)
			)
			(layer "F.SilkS")
		)
		(fp_line
			(start -0.67945 -0.305054)
			(end -0.12065 -0.305054)
			(stroke
				(width 0.1)
				(type default)
			)
			(layer "F.Fab")
		)
		(fp_line
			(start -0.67945 0.3048)
			(end -0.67945 -0.305054)
			(stroke
				(width 0.1)
				(type default)
			)
			(layer "F.Fab")
		)
		(fp_line
			(start -0.12065 -0.305054)
			(end -0.12065 -0.2794)
			(stroke
				(width 0.1)
				(type default)
			)
			(layer "F.Fab")
		)
		(fp_line
			(start -0.12065 -0.2794)
			(end 0.12065 -0.2794)
			(stroke
				(width 0.1)
				(type default)
			)
			(layer "F.Fab")
		)
		(fp_line
			(start -0.12065 0.2794)
			(end -0.12065 0.3048)
			(stroke
				(width 0.1)
				(type default)
			)
			(layer "F.Fab")
		)
		(fp_line
			(start -0.12065 0.3048)
			(end -0.67945 0.3048)
			(stroke
				(width 0.1)
				(type default)
			)
			(layer "F.Fab")
		)
		(fp_line
			(start 0.120396 0.2794)
			(end -0.12065 0.2794)
			(stroke
				(width 0.1)
				(type default)
			)
			(layer "F.Fab")
		)
		(fp_line
			(start 0.120396 0.3048)
			(end 0.120396 0.2794)
			(stroke
				(width 0.1)
				(type default)
			)
			(layer "F.Fab")
		)
		(fp_line
			(start 0.12065 -0.3048)
			(end 0.67945 -0.3048)
			(stroke
				(width 0.1)
				(type default)
			)
			(layer "F.Fab")
		)
		(fp_line
			(start 0.12065 -0.2794)
			(end 0.12065 -0.3048)
			(stroke
				(width 0.1)
				(type default)
			)
			(layer "F.Fab")
		)
		(fp_line
			(start 0.67945 -0.3048)
			(end 0.67945 0.3048)
			(stroke
				(width 0.1)
				(type default)
			)
			(layer "F.Fab")
		)
		(fp_line
			(start 0.67945 0.3048)
			(end 0.120396 0.3048)
			(stroke
				(width 0.1)
				(type default)
			)
			(layer "F.Fab")
		)
		(pad "1" smd circle
			(at -0.40005 0)
			(size 0 0)
			(layers "F.Cu" "F.Mask" "F.Paste")
			(net "P3V3_AUX")
		)
		(pad "2" smd circle
			(at 0.40005 0)
			(size 0 0)
			(layers "F.Cu" "F.Mask" "F.Paste")
			(net "SMB_2_BMC_GPU_BUF_R_SDA")
		)
	)
	(footprint ""
		(layer "F.Cu")
		(at 353.36988 -296.05478 180)
		(property "Reference" "C214"
			(at 0 0 180)
			(layer "F.SilkS")
			(hide yes)
			(effects
				(font
					(size 1.27 1.27)
				)
			)
		)
		(property "Value" ""
			(at 0 0 180)
			(layer "F.Fab")
			(effects
				(font
					(size 1.27 1.27)
				)
			)
		)
		(duplicate_pad_numbers_are_jumpers no)
		(fp_line
			(start 1.524 0.762)
			(end -1.524 0.762)
			(stroke
				(width 0.1524)
				(type default)
			)
			(layer "F.SilkS")
		)
		(fp_line
			(start 1.524 -0.762)
			(end 1.524 0.762)
			(stroke
				(width 0.1524)
				(type default)
			)
			(layer "F.SilkS")
		)
		(fp_line
			(start -1.524 0.762)
			(end -1.524 -0.762)
			(stroke
				(width 0.1524)
				(type default)
			)
			(layer "F.SilkS")
		)
		(fp_line
			(start -1.524 -0.762)
			(end 1.524 -0.762)
			(stroke
				(width 0.1524)
				(type default)
			)
			(layer "F.SilkS")
		)
		(fp_line
			(start 1.1049 0.724916)
			(end 1.1049 -0.724916)
			(stroke
				(width 0.1)
				(type default)
			)
			(layer "F.Fab")
		)
		(fp_line
			(start 1.1049 -0.724916)
			(end -1.1049 -0.724916)
			(stroke
				(width 0.1)
				(type default)
			)
			(layer "F.Fab")
		)
		(fp_line
			(start -1.1049 0.724916)
			(end 1.1049 0.724916)
			(stroke
				(width 0.1)
				(type default)
			)
			(layer "F.Fab")
		)
		(fp_line
			(start -1.1049 -0.724916)
			(end -1.1049 0.724916)
			(stroke
				(width 0.1)
				(type default)
			)
			(layer "F.Fab")
		)
		(pad "1" smd rect
			(at -0.889 0)
			(size 1.016 1.27)
			(layers "F.Cu" "F.Mask" "F.Paste")
			(net "PVCCIN_CPU0")
		)
		(pad "2" smd rect
			(at 0.889 0)
			(size 1.016 1.27)
			(layers "F.Cu" "F.Mask" "F.Paste")
			(net "GND")
		)
	)
	(footprint ""
		(layer "F.Cu")
		(at 423.8498 -16.088614 90)
		(property "Reference" "C863"
			(at 0 0 90)
			(layer "F.SilkS")
			(hide yes)
			(effects
				(font
					(size 1.27 1.27)
				)
			)
		)
		(property "Value" ""
			(at 0 0 90)
			(layer "F.Fab")
			(effects
				(font
					(size 1.27 1.27)
				)
			)
		)
		(duplicate_pad_numbers_are_jumpers no)
		(fp_line
			(start 0.299974 -0.150114)
			(end 0.299974 0.150114)
			(stroke
				(width 0.1)
				(type default)
			)
			(layer "F.Fab")
		)
		(fp_line
			(start -0.299974 -0.150114)
			(end 0.299974 -0.150114)
			(stroke
				(width 0.1)
				(type default)
			)
			(layer "F.Fab")
		)
		(fp_line
			(start 0.299974 0.150114)
			(end -0.299974 0.150114)
			(stroke
				(width 0.1)
				(type default)
			)
			(layer "F.Fab")
		)
		(fp_line
			(start -0.299974 0.150114)
			(end -0.299974 -0.150114)
			(stroke
				(width 0.1)
				(type default)
			)
			(layer "F.Fab")
		)
		(pad "1" smd rect
			(at -0.2667 0 90)
			(size 0.3048 0.381)
			(layers "F.Cu" "F.Mask" "F.Paste")
			(net "P5E_CPU0_PE1_TX_C_DP<3>")
		)
		(pad "2" smd rect
			(at 0.2667 0 90)
			(size 0.3048 0.381)
			(layers "F.Cu" "F.Mask" "F.Paste")
			(net "P5E_CPU0_PE1_TX_DP<3>")
		)
	)
	(footprint ""
		(layer "F.Cu")
		(at 56.349138 -360.92765)
		(property "Reference" "PC1677"
			(at 0 0 0)
			(layer "F.SilkS")
			(hide yes)
			(effects
				(font
					(size 1.27 1.27)
				)
			)
		)
		(property "Value" ""
			(at 0 0 0)
			(layer "F.Fab")
			(effects
				(font
					(size 1.27 1.27)
				)
			)
		)
		(duplicate_pad_numbers_are_jumpers no)
		(fp_line
			(start -1.524 -0.762)
			(end 1.524 -0.762)
			(stroke
				(width 0.1524)
				(type default)
			)
			(layer "F.SilkS")
		)
		(fp_line
			(start -1.524 0.762)
			(end -1.524 -0.762)
			(stroke
				(width 0.1524)
				(type default)
			)
			(layer "F.SilkS")
		)
		(fp_line
			(start 1.524 -0.762)
			(end 1.524 0.762)
			(stroke
				(width 0.1524)
				(type default)
			)
			(layer "F.SilkS")
		)
		(fp_line
			(start 1.524 0.762)
			(end -1.524 0.762)
			(stroke
				(width 0.1524)
				(type default)
			)
			(layer "F.SilkS")
		)
		(fp_line
			(start -1.1049 -0.724916)
			(end -1.1049 0.724916)
			(stroke
				(width 0.1)
				(type default)
			)
			(layer "F.Fab")
		)
		(fp_line
			(start -1.1049 0.724916)
			(end 1.1049 0.724916)
			(stroke
				(width 0.1)
				(type default)
			)
			(layer "F.Fab")
		)
		(fp_line
			(start 1.1049 -0.724916)
			(end -1.1049 -0.724916)
			(stroke
				(width 0.1)
				(type default)
			)
			(layer "F.Fab")
		)
		(fp_line
			(start 1.1049 0.724916)
			(end 1.1049 -0.724916)
			(stroke
				(width 0.1)
				(type default)
			)
			(layer "F.Fab")
		)
		(pad "1" smd rect
			(at -0.889 0 180)
			(size 1.016 1.27)
			(layers "F.Cu" "F.Mask" "F.Paste")
			(net "SW_P12V_PVCCFA_EHV_FIVRA_CPU1_L")
		)
		(pad "2" smd rect
			(at 0.889 0 180)
			(size 1.016 1.27)
			(layers "F.Cu" "F.Mask" "F.Paste")
			(net "GND")
		)
	)
	(footprint ""
		(layer "F.Cu")
		(at 46.582584 -112.619282 180)
		(property "Reference" "R1799"
			(at 0 0 180)
			(layer "F.SilkS")
			(hide yes)
			(effects
				(font
					(size 1.27 1.27)
				)
			)
		)
		(property "Value" ""
			(at 0 0 180)
			(layer "F.Fab")
			(effects
				(font
					(size 1.27 1.27)
				)
			)
		)
		(duplicate_pad_numbers_are_jumpers no)
		(fp_line
			(start 0.7874 0.4064)
			(end -0.7874 0.4064)
			(stroke
				(width 0.1524)
				(type default)
			)
			(layer "F.SilkS")
		)
		(fp_line
			(start 0.7874 -0.4064)
			(end 0.7874 0.4064)
			(stroke
				(width 0.1524)
				(type default)
			)
			(layer "F.SilkS")
		)
		(fp_line
			(start -0.7874 0.4064)
			(end -0.7874 -0.4064)
			(stroke
				(width 0.1524)
				(type default)
			)
			(layer "F.SilkS")
		)
		(fp_line
			(start -0.7874 -0.4064)
			(end 0.7874 -0.4064)
			(stroke
				(width 0.1524)
				(type default)
			)
			(layer "F.SilkS")
		)
		(fp_line
			(start 0.67945 0.3048)
			(end 0.120396 0.3048)
			(stroke
				(width 0.1)
				(type default)
			)
			(layer "F.Fab")
		)
		(fp_line
			(start 0.67945 -0.3048)
			(end 0.67945 0.3048)
			(stroke
				(width 0.1)
				(type default)
			)
			(layer "F.Fab")
		)
		(fp_line
			(start 0.12065 -0.2794)
			(end 0.12065 -0.3048)
			(stroke
				(width 0.1)
				(type default)
			)
			(layer "F.Fab")
		)
		(fp_line
			(start 0.12065 -0.3048)
			(end 0.67945 -0.3048)
			(stroke
				(width 0.1)
				(type default)
			)
			(layer "F.Fab")
		)
		(fp_line
			(start 0.120396 0.3048)
			(end 0.120396 0.2794)
			(stroke
				(width 0.1)
				(type default)
			)
			(layer "F.Fab")
		)
		(fp_line
			(start 0.120396 0.2794)
			(end -0.12065 0.2794)
			(stroke
				(width 0.1)
				(type default)
			)
			(layer "F.Fab")
		)
		(fp_line
			(start -0.12065 0.3048)
			(end -0.67945 0.3048)
			(stroke
				(width 0.1)
				(type default)
			)
			(layer "F.Fab")
		)
		(fp_line
			(start -0.12065 0.2794)
			(end -0.12065 0.3048)
			(stroke
				(width 0.1)
				(type default)
			)
			(layer "F.Fab")
		)
		(fp_line
			(start -0.12065 -0.2794)
			(end 0.12065 -0.2794)
			(stroke
				(width 0.1)
				(type default)
			)
			(layer "F.Fab")
		)
		(fp_line
			(start -0.12065 -0.305054)
			(end -0.12065 -0.2794)
			(stroke
				(width 0.1)
				(type default)
			)
			(layer "F.Fab")
		)
		(fp_line
			(start -0.67945 0.3048)
			(end -0.67945 -0.305054)
			(stroke
				(width 0.1)
				(type default)
			)
			(layer "F.Fab")
		)
		(fp_line
			(start -0.67945 -0.305054)
			(end -0.12065 -0.305054)
			(stroke
				(width 0.1)
				(type default)
			)
			(layer "F.Fab")
		)
		(pad "1" smd circle
			(at -0.40005 0 180)
			(size 0 0)
			(layers "F.Cu" "F.Mask" "F.Paste")
			(net "P12V_AUX")
		)
		(pad "2" smd circle
			(at 0.40005 0 180)
			(size 0 0)
			(layers "F.Cu" "F.Mask" "F.Paste")
			(net "P12V_AUX_ADC")
		)
	)
	(footprint ""
		(layer "F.Cu")
		(at 325.072248 -342.786208 -90)
		(property "Reference" "PC229_P0_7"
			(at 0 0 270)
			(layer "F.SilkS")
			(hide yes)
			(effects
				(font
					(size 1.27 1.27)
				)
			)
		)
		(property "Value" ""
			(at 0 0 270)
			(layer "F.Fab")
			(effects
				(font
					(size 1.27 1.27)
				)
			)
		)
		(duplicate_pad_numbers_are_jumpers no)
		(fp_line
			(start -0.7874 0.4064)
			(end -0.7874 -0.4064)
			(stroke
				(width 0.1524)
				(type default)
			)
			(layer "F.SilkS")
		)
		(fp_line
			(start 0.7874 0.4064)
			(end -0.7874 0.4064)
			(stroke
				(width 0.1524)
				(type default)
			)
			(layer "F.SilkS")
		)
		(fp_line
			(start -0.7874 -0.4064)
			(end 0.7874 -0.4064)
			(stroke
				(width 0.1524)
				(type default)
			)
			(layer "F.SilkS")
		)
		(fp_line
			(start 0.7874 -0.4064)
			(end 0.7874 0.4064)
			(stroke
				(width 0.1524)
				(type default)
			)
			(layer "F.SilkS")
		)
		(fp_line
			(start -0.67945 0.3048)
			(end -0.67945 -0.305054)
			(stroke
				(width 0.1)
				(type default)
			)
			(layer "F.Fab")
		)
		(fp_line
			(start -0.12065 0.3048)
			(end -0.67945 0.3048)
			(stroke
				(width 0.1)
				(type default)
			)
			(layer "F.Fab")
		)
		(fp_line
			(start 0.120396 0.3048)
			(end 0.120396 0.2794)
			(stroke
				(width 0.1)
				(type default)
			)
			(layer "F.Fab")
		)
		(fp_line
			(start 0.67945 0.3048)
			(end 0.120396 0.3048)
			(stroke
				(width 0.1)
				(type default)
			)
			(layer "F.Fab")
		)
		(fp_line
			(start -0.12065 0.2794)
			(end -0.12065 0.3048)
			(stroke
				(width 0.1)
				(type default)
			)
			(layer "F.Fab")
		)
		(fp_line
			(start 0.120396 0.2794)
			(end -0.12065 0.2794)
			(stroke
				(width 0.1)
				(type default)
			)
			(layer "F.Fab")
		)
		(fp_line
			(start -0.12065 -0.2794)
			(end 0.12065 -0.2794)
			(stroke
				(width 0.1)
				(type default)
			)
			(layer "F.Fab")
		)
		(fp_line
			(start 0.12065 -0.2794)
			(end 0.12065 -0.3048)
			(stroke
				(width 0.1)
				(type default)
			)
			(layer "F.Fab")
		)
		(fp_line
			(start 0.12065 -0.3048)
			(end 0.67945 -0.3048)
			(stroke
				(width 0.1)
				(type default)
			)
			(layer "F.Fab")
		)
		(fp_line
			(start 0.67945 -0.3048)
			(end 0.67945 0.3048)
			(stroke
				(width 0.1)
				(type default)
			)
			(layer "F.Fab")
		)
		(fp_line
			(start -0.67945 -0.305054)
			(end -0.12065 -0.305054)
			(stroke
				(width 0.1)
				(type default)
			)
			(layer "F.Fab")
		)
		(fp_line
			(start -0.12065 -0.305054)
			(end -0.12065 -0.2794)
			(stroke
				(width 0.1)
				(type default)
			)
			(layer "F.Fab")
		)
		(pad "1" smd circle
			(at -0.40005 0 270)
			(size 0 0)
			(layers "F.Cu" "F.Mask" "F.Paste")
			(net "PVCCIN_CPU0_PVCC")
		)
		(pad "2" smd circle
			(at 0.40005 0 270)
			(size 0 0)
			(layers "F.Cu" "F.Mask" "F.Paste")
			(net "GND")
		)
	)
	(footprint ""
		(layer "F.Cu")
		(at 414.28289 -402.371052 -90)
		(property "Reference" "C963"
			(at 0 0 270)
			(layer "F.SilkS")
			(hide yes)
			(effects
				(font
					(size 1.27 1.27)
				)
			)
		)
		(property "Value" ""
			(at 0 0 270)
			(layer "F.Fab")
			(effects
				(font
					(size 1.27 1.27)
				)
			)
		)
		(duplicate_pad_numbers_are_jumpers no)
		(fp_line
			(start -0.299974 0.150114)
			(end -0.299974 -0.150114)
			(stroke
				(width 0.1)
				(type default)
			)
			(layer "F.Fab")
		)
		(fp_line
			(start 0.299974 0.150114)
			(end -0.299974 0.150114)
			(stroke
				(width 0.1)
				(type default)
			)
			(layer "F.Fab")
		)
		(fp_line
			(start -0.299974 -0.150114)
			(end 0.299974 -0.150114)
			(stroke
				(width 0.1)
				(type default)
			)
			(layer "F.Fab")
		)
		(fp_line
			(start 0.299974 -0.150114)
			(end 0.299974 0.150114)
			(stroke
				(width 0.1)
				(type default)
			)
			(layer "F.Fab")
		)
		(pad "1" smd rect
			(at -0.2667 0 270)
			(size 0.3048 0.381)
			(layers "F.Cu" "F.Mask" "F.Paste")
			(net "P5E_CPU0_PE2_TX_C_DP<1>")
		)
		(pad "2" smd rect
			(at 0.2667 0 270)
			(size 0.3048 0.381)
			(layers "F.Cu" "F.Mask" "F.Paste")
			(net "P5E_CPU0_PE2_TX_DP<1>")
		)
	)
	(footprint ""
		(layer "F.Cu")
		(at 196.729604 -77.06614 180)
		(property "Reference" "R1351"
			(at 0 0 180)
			(layer "F.SilkS")
			(hide yes)
			(effects
				(font
					(size 1.27 1.27)
				)
			)
		)
		(property "Value" ""
			(at 0 0 180)
			(layer "F.Fab")
			(effects
				(font
					(size 1.27 1.27)
				)
			)
		)
		(duplicate_pad_numbers_are_jumpers no)
		(fp_line
			(start 0.7874 0.4064)
			(end -0.7874 0.4064)
			(stroke
				(width 0.1524)
				(type default)
			)
			(layer "F.SilkS")
		)
		(fp_line
			(start 0.7874 -0.4064)
			(end 0.7874 0.4064)
			(stroke
				(width 0.1524)
				(type default)
			)
			(layer "F.SilkS")
		)
		(fp_line
			(start -0.7874 0.4064)
			(end -0.7874 -0.4064)
			(stroke
				(width 0.1524)
				(type default)
			)
			(layer "F.SilkS")
		)
		(fp_line
			(start -0.7874 -0.4064)
			(end 0.7874 -0.4064)
			(stroke
				(width 0.1524)
				(type default)
			)
			(layer "F.SilkS")
		)
		(fp_line
			(start 0.67945 0.3048)
			(end 0.120396 0.3048)
			(stroke
				(width 0.1)
				(type default)
			)
			(layer "F.Fab")
		)
		(fp_line
			(start 0.67945 -0.3048)
			(end 0.67945 0.3048)
			(stroke
				(width 0.1)
				(type default)
			)
			(layer "F.Fab")
		)
		(fp_line
			(start 0.12065 -0.2794)
			(end 0.12065 -0.3048)
			(stroke
				(width 0.1)
				(type default)
			)
			(layer "F.Fab")
		)
		(fp_line
			(start 0.12065 -0.3048)
			(end 0.67945 -0.3048)
			(stroke
				(width 0.1)
				(type default)
			)
			(layer "F.Fab")
		)
		(fp_line
			(start 0.120396 0.3048)
			(end 0.120396 0.2794)
			(stroke
				(width 0.1)
				(type default)
			)
			(layer "F.Fab")
		)
		(fp_line
			(start 0.120396 0.2794)
			(end -0.12065 0.2794)
			(stroke
				(width 0.1)
				(type default)
			)
			(layer "F.Fab")
		)
		(fp_line
			(start -0.12065 0.3048)
			(end -0.67945 0.3048)
			(stroke
				(width 0.1)
				(type default)
			)
			(layer "F.Fab")
		)
		(fp_line
			(start -0.12065 0.2794)
			(end -0.12065 0.3048)
			(stroke
				(width 0.1)
				(type default)
			)
			(layer "F.Fab")
		)
		(fp_line
			(start -0.12065 -0.2794)
			(end 0.12065 -0.2794)
			(stroke
				(width 0.1)
				(type default)
			)
			(layer "F.Fab")
		)
		(fp_line
			(start -0.12065 -0.305054)
			(end -0.12065 -0.2794)
			(stroke
				(width 0.1)
				(type default)
			)
			(layer "F.Fab")
		)
		(fp_line
			(start -0.67945 0.3048)
			(end -0.67945 -0.305054)
			(stroke
				(width 0.1)
				(type default)
			)
			(layer "F.Fab")
		)
		(fp_line
			(start -0.67945 -0.305054)
			(end -0.12065 -0.305054)
			(stroke
				(width 0.1)
				(type default)
			)
			(layer "F.Fab")
		)
		(pad "1" smd circle
			(at -0.40005 0 180)
			(size 0 0)
			(layers "F.Cu" "F.Mask" "F.Paste")
			(net "RMII_OCP_BMC_RXD_0")
		)
		(pad "2" smd circle
			(at 0.40005 0 180)
			(size 0 0)
			(layers "F.Cu" "F.Mask" "F.Paste")
			(net "GND")
		)
	)
)
